(kicad_pcb
	(version 20241229)
	(generator "pcbnew")
	(generator_version "9.0")
	(general
		(thickness 1.63)
		(legacy_teardrops no)
	)
	(paper "A4")
	(title_block
		(title "CM4 Baseboard")
		(date "2026-01-05")
		(rev "1.1.1")
		(company "Antmicro Ltd")
		(comment 1 "www.antmicro.com")
		(comment 9 "footprints 387-389 of 506")
	)
	(layers
		(0 "F.Cu" signal)
		(4 "In1.Cu" power)
		(6 "In2.Cu" power)
		(8 "In3.Cu" signal)
		(10 "In4.Cu" signal)
		(2 "B.Cu" signal)
		(9 "F.Adhes" user "F.Adhesive")
		(11 "B.Adhes" user "B.Adhesive")
		(13 "F.Paste" user)
		(15 "B.Paste" user)
		(5 "F.SilkS" user "F.Silkscreen")
		(7 "B.SilkS" user "B.Silkscreen")
		(1 "F.Mask" user)
		(3 "B.Mask" user)
		(17 "Dwgs.User" user "User.Drawings")
		(19 "Cmts.User" user "User.Comments")
		(21 "Eco1.User" user "User.Eco1")
		(23 "Eco2.User" user "User.Eco2")
		(25 "Edge.Cuts" user)
		(27 "Margin" user)
		(31 "F.CrtYd" user "F.Courtyard")
		(29 "B.CrtYd" user "B.Courtyard")
		(35 "F.Fab" user)
		(33 "B.Fab" user)
	)
	(footprint "antmicro-footprints:SOT-363"
		(layer "B.Cu")
		(at 60.142962 163.6665)
		(property "Reference" "Q302"
			(at 2.185 1.95 90)
			(layer "B.SilkS")
			(effects
				(font
					(size 0.7 0.7)
					(thickness 0.15)
				)
				(justify right bottom mirror)
			)
		)
		(property "Value" "DZDH0401DW"
			(at 0 -2.2 0)
			(layer "B.Fab")
			(effects
				(font
					(size 0.7 0.7)
					(thickness 0.15)
				)
				(justify right bottom mirror)
			)
		)
		(property "Datasheet" "https://www.mouser.com/datasheet/2/115/DIOD_S_A0011803041_1-2543705.pdf"
			(at 0 0 0)
			(layer "B.Fab")
			(hide yes)
			(effects
				(font
					(size 1.27 1.27)
					(thickness 0.15)
				)
			)
		)
		(property "MPN" "DZDH0401DW"
			(at 0 0 0)
			(unlocked yes)
			(layer "B.Fab")
			(hide yes)
			(effects
				(font
					(size 1 1)
					(thickness 0.15)
				)
				(justify mirror)
			)
		)
		(property "Manufacturer" "Diodes Incorporated"
			(at 0 0 0)
			(unlocked yes)
			(layer "B.Fab")
			(hide yes)
			(effects
				(font
					(size 1 1)
					(thickness 0.15)
				)
				(justify mirror)
			)
		)
		(property "Author" "Antmicro"
			(at 0 0 0)
			(unlocked yes)
			(layer "B.Fab")
			(hide yes)
			(effects
				(font
					(size 1 1)
					(thickness 0.15)
				)
				(justify mirror)
			)
		)
		(property "License" "Apache-2.0"
			(at 0 0 0)
			(unlocked yes)
			(layer "B.Fab")
			(hide yes)
			(effects
				(font
					(size 1 1)
					(thickness 0.15)
				)
				(justify mirror)
			)
		)
		(sheetname "/Supply/")
		(sheetfile "supply.kicad_sch")
		(attr smd)
		(fp_line
			(start -0.8 -1.223)
			(end 0.803 -1.223)
			(stroke
				(width 0.15)
				(type solid)
			)
			(layer "B.SilkS")
		)
		(fp_line
			(start -0.8 -1.146)
			(end -0.8 -1.223)
			(stroke
				(width 0.15)
				(type solid)
			)
			(layer "B.SilkS")
		)
		(fp_line
			(start -0.72 1.153)
			(end -0.72 1.228)
			(stroke
				(width 0.15)
				(type solid)
			)
			(layer "B.SilkS")
		)
		(fp_line
			(start 0.803 -1.146)
			(end 0.803 -1.223)
			(stroke
				(width 0.15)
				(type solid)
			)
			(layer "B.SilkS")
		)
		(fp_line
			(start 0.803 1.153)
			(end 0.803 1.228)
			(stroke
				(width 0.15)
				(type solid)
			)
			(layer "B.SilkS")
		)
		(fp_line
			(start 0.803 1.228)
			(end -0.72 1.228)
			(stroke
				(width 0.15)
				(type solid)
			)
			(layer "B.SilkS")
		)
		(fp_circle
			(center -0.978102 1.2)
			(end -0.928102 1.2)
			(stroke
				(width 0.15)
				(type solid)
			)
			(fill yes)
			(layer "B.SilkS")
		)
		(fp_rect
			(start 1.3 1.3)
			(end -1.3 -1.3)
			(stroke
				(width 0.05)
				(type solid)
			)
			(fill no)
			(layer "B.CrtYd")
		)
		(fp_line
			(start -0.1 1.1)
			(end -0.68 0.52)
			(stroke
				(width 0.15)
				(type solid)
			)
			(layer "B.Fab")
		)
		(fp_rect
			(start 0.68 -1.1)
			(end -0.68 1.1)
			(stroke
				(width 0.15)
				(type solid)
			)
			(fill no)
			(layer "B.Fab")
		)
		(fp_text user "Author: Antmicro"
			(at -1.3 -6.4 180)
			(layer "B.Fab")
			(effects
				(font
					(size 0.7 0.7)
					(thickness 0.15)
				)
				(justify left bottom mirror)
			)
		)
		(fp_text user "${REFERENCE}"
			(at -1.3 -4 180)
			(layer "B.Fab")
			(effects
				(font
					(size 0.7 0.7)
					(thickness 0.15)
				)
				(justify left bottom mirror)
			)
		)
		(fp_text user "License: Apache-2.0"
			(at -1.3 -5.2 180)
			(layer "B.Fab")
			(effects
				(font
					(size 0.7 0.7)
					(thickness 0.15)
				)
				(justify left bottom mirror)
			)
		)
		(pad "1" smd custom
			(at -0.948 0.752 90)
			(size 0.6 0.6)
			(layers "B.Cu" "B.Mask" "B.Paste")
			(net 494 "unconnected-(Q302-NC-Pad1)")
			(pinfunction "NC")
			(pintype "no_connect")
			(options
				(clearance outline)
				(anchor rect)
			)
			(primitives)
		)
		(pad "2" smd rect
			(at -0.948 0.002 90)
			(size 0.4 0.6)
			(layers "B.Cu" "B.Mask" "B.Paste")
			(net 334 "Net-(Q302-REF)")
			(pinfunction "REF")
			(pintype "input")
		)
		(pad "3" smd custom
			(at -0.948 -0.745 90)
			(size 0.6 0.6)
			(layers "B.Cu" "B.Mask" "B.Paste")
			(net 335 "Net-(Q302-BIAS)")
			(pinfunction "BIAS")
			(pintype "output")
			(options
				(clearance outline)
				(anchor rect)
			)
			(primitives)
		)
		(pad "4" smd custom
			(at 0.951 -0.745 90)
			(size 0.6 0.6)
			(layers "B.Cu" "B.Mask" "B.Paste")
			(net 21 "/Supply/VCC_IN")
			(pinfunction "S")
			(pintype "power_in")
			(options
				(clearance outline)
				(anchor rect)
			)
			(primitives)
		)
		(pad "5" smd rect
			(at 0.951 0.002 90)
			(size 0.4 0.6)
			(layers "B.Cu" "B.Mask" "B.Paste")
			(net 495 "unconnected-(Q302-NC-Pad5)")
			(pinfunction "NC")
			(pintype "no_connect")
		)
		(pad "6" smd custom
			(at 0.951 0.752 90)
			(size 0.6 0.6)
			(layers "B.Cu" "B.Mask" "B.Paste")
			(net 47 "/Ethernet/POE_12V")
			(pinfunction "D")
			(pintype "power_in")
			(options
				(clearance outline)
				(anchor rect)
			)
			(primitives)
		)
	)
	(footprint "antmicro-footprints:R_0402_1005Metric"
		(layer "B.Cu")
		(at 84.937962 164.1365)
		(descr "Resistor SMD 0402")
		(tags "resistor SMD 0402")
		(property "Reference" "R208"
			(at -3.62 0.53 0)
			(layer "B.SilkS")
			(effects
				(font
					(size 0.7 0.7)
					(thickness 0.15)
				)
				(justify right bottom mirror)
			)
		)
		(property "Value" "R_0R_0402"
			(at -1.011843 -1.772047 0)
			(layer "B.Fab")
			(effects
				(font
					(size 0.7 0.7)
					(thickness 0.15)
				)
				(justify right bottom mirror)
			)
		)
		(property "Datasheet" "https://industrial.panasonic.com/cdbs/www-data/pdf/RDA0000/AOA0000C301.pdf"
			(at 0 0 0)
			(layer "B.Fab")
			(hide yes)
			(effects
				(font
					(size 1.27 1.27)
					(thickness 0.15)
				)
			)
		)
		(property "Manufacturer" "Panasonic"
			(at 0 0 0)
			(unlocked yes)
			(layer "B.Fab")
			(hide yes)
			(effects
				(font
					(size 1 1)
					(thickness 0.15)
				)
				(justify mirror)
			)
		)
		(property "MPN" "ERJ2GE0R00X"
			(at 0 0 0)
			(unlocked yes)
			(layer "B.Fab")
			(hide yes)
			(effects
				(font
					(size 1 1)
					(thickness 0.15)
				)
				(justify mirror)
			)
		)
		(property "Val" "0R"
			(at 0 0 0)
			(unlocked yes)
			(layer "B.Fab")
			(hide yes)
			(effects
				(font
					(size 1 1)
					(thickness 0.15)
				)
				(justify mirror)
			)
		)
		(property "License" "Apache-2.0"
			(at 0 0 0)
			(unlocked yes)
			(layer "B.Fab")
			(hide yes)
			(effects
				(font
					(size 1 1)
					(thickness 0.15)
				)
				(justify mirror)
			)
		)
		(property "Author" "Antmicro"
			(at 0 0 0)
			(unlocked yes)
			(layer "B.Fab")
			(hide yes)
			(effects
				(font
					(size 1 1)
					(thickness 0.15)
				)
				(justify mirror)
			)
		)
		(property "Tolerance" "~"
			(at 0 0 0)
			(unlocked yes)
			(layer "B.Fab")
			(hide yes)
			(effects
				(font
					(size 1 1)
					(thickness 0.15)
				)
				(justify mirror)
			)
		)
		(property "Current" "1A"
			(at 0 0 0)
			(unlocked yes)
			(layer "B.Fab")
			(hide yes)
			(effects
				(font
					(size 1 1)
					(thickness 0.15)
				)
				(justify mirror)
			)
		)
		(sheetname "/Compute module/")
		(sheetfile "compute-module.kicad_sch")
		(attr smd exclude_from_pos_files exclude_from_bom dnp)
		(fp_rect
			(start -0.925 0.47)
			(end 0.925 -0.47)
			(stroke
				(width 0.05)
				(type default)
			)
			(fill no)
			(layer "B.CrtYd")
		)
		(fp_rect
			(start -0.5 0.25)
			(end 0.5 -0.25)
			(stroke
				(width 0.15)
				(type solid)
			)
			(fill no)
			(layer "B.Fab")
		)
		(fp_text user "License: Apache-2.0"
			(at -0.95 -5.169 180)
			(layer "B.Fab")
			(effects
				(font
					(size 0.7 0.7)
					(thickness 0.15)
				)
				(justify left bottom mirror)
			)
		)
		(fp_text user "Author: Antmicro"
			(at -0.95 -4.169 180)
			(layer "B.Fab")
			(effects
				(font
					(size 0.7 0.7)
					(thickness 0.15)
				)
				(justify left bottom mirror)
			)
		)
		(fp_text user "${REFERENCE}"
			(at -0.95 -3.168 180)
			(layer "B.Fab")
			(effects
				(font
					(size 0.7 0.7)
					(thickness 0.15)
				)
				(justify left bottom mirror)
			)
		)
		(pad "1" smd roundrect
			(at -0.48 0)
			(size 0.59 0.64)
			(layers "B.Cu" "B.Mask" "B.Paste")
			(roundrect_rratio 0.25)
			(net 254 "/Compute module/CAM_GPIO")
			(pintype "passive")
		)
		(pad "2" smd roundrect
			(at 0.48 0)
			(size 0.59 0.64)
			(layers "B.Cu" "B.Mask" "B.Paste")
			(roundrect_rratio 0.25)
			(net 274 "/CSI/CamCtrl.VSYNC0")
			(pintype "passive")
		)
	)
	(footprint "antmicro-footprints:MicroSD_Amphenol_1140084168"
		(layer "B.Cu")
		(at 133.800462 163.5665 -90)
		(property "Reference" "J502"
			(at -6.72 -5.9675 0)
			(layer "B.SilkS")
			(effects
				(font
					(size 0.7 0.7)
					(thickness 0.15)
				)
				(justify right bottom mirror)
			)
		)
		(property "Value" "MicroSD_1140084168"
			(at -6.9 -11.4 90)
			(layer "B.Fab")
			(effects
				(font
					(size 0.7 0.7)
					(thickness 0.15)
				)
				(justify left bottom mirror)
			)
		)
		(property "Datasheet" "https://cdn.amphenol-cs.com/media/wysiwyg/files/documentation/datasheet/inputoutput/io_micro_sdcard.pdf"
			(at 0 0 270)
			(layer "B.Fab")
			(hide yes)
			(effects
				(font
					(size 1.27 1.27)
					(thickness 0.15)
				)
			)
		)
		(property "MPN" "1140084168"
			(at 0 0 270)
			(unlocked yes)
			(layer "B.Fab")
			(hide yes)
			(effects
				(font
					(size 1 1)
					(thickness 0.15)
				)
				(justify mirror)
			)
		)
		(property "Manufacturer" "Amphenol"
			(at 0 0 270)
			(unlocked yes)
			(layer "B.Fab")
			(hide yes)
			(effects
				(font
					(size 1 1)
					(thickness 0.15)
				)
				(justify mirror)
			)
		)
		(property "Author" "Antmicro"
			(at 0 0 270)
			(unlocked yes)
			(layer "B.Fab")
			(hide yes)
			(effects
				(font
					(size 1 1)
					(thickness 0.15)
				)
				(justify mirror)
			)
		)
		(property "License" "Apache-2.0"
			(at 0 0 270)
			(unlocked yes)
			(layer "B.Fab")
			(hide yes)
			(effects
				(font
					(size 1 1)
					(thickness 0.15)
				)
				(justify mirror)
			)
		)
		(sheetname "/NVMe & microSD/")
		(sheetfile "nvme-micro-sd.kicad_sch")
		(attr smd)
		(fp_line
			(start -6.3 6.1)
			(end -6.3 4.7)
			(stroke
				(width 0.15)
				(type solid)
			)
			(layer "B.SilkS")
		)
		(fp_line
			(start 4.8 6.1)
			(end -6.3 6.1)
			(stroke
				(width 0.15)
				(type solid)
			)
			(layer "B.SilkS")
		)
		(fp_line
			(start 6.2 6.1)
			(end 6.1 6.1)
			(stroke
				(width 0.15)
				(type solid)
			)
			(layer "B.SilkS")
		)
		(fp_line
			(start 6.2 4)
			(end 6.2 6.1)
			(stroke
				(width 0.15)
				(type solid)
			)
			(layer "B.SilkS")
		)
		(fp_line
			(start -6.3 1.6)
			(end -6.3 -4.2)
			(stroke
				(width 0.15)
				(type solid)
			)
			(layer "B.SilkS")
		)
		(fp_line
			(start 6.2 -4.2)
			(end 6.2 2.2)
			(stroke
				(width 0.15)
				(type solid)
			)
			(layer "B.SilkS")
		)
		(fp_rect
			(start -6.5 6.3)
			(end 6.4 -6.2)
			(stroke
				(width 0.05)
				(type solid)
			)
			(fill no)
			(layer "B.CrtYd")
		)
		(fp_line
			(start -5.6 -5.8)
			(end -5.6 -9.5)
			(stroke
				(width 0.12)
				(type solid)
			)
			(layer "B.Fab")
		)
		(fp_line
			(start -1 -8.2)
			(end -2.3 -8.3)
			(stroke
				(width 0.12)
				(type solid)
			)
			(layer "B.Fab")
		)
		(fp_line
			(start 0.8 -8.2)
			(end -1 -8.2)
			(stroke
				(width 0.12)
				(type solid)
			)
			(layer "B.Fab")
		)
		(fp_line
			(start -2.3 -8.3)
			(end -3.8 -8.5)
			(stroke
				(width 0.12)
				(type solid)
			)
			(layer "B.Fab")
		)
		(fp_line
			(start 2.1 -8.3)
			(end 0.8 -8.2)
			(stroke
				(width 0.12)
				(type solid)
			)
			(layer "B.Fab")
		)
		(fp_line
			(start 2.9 -8.4)
			(end 2.1 -8.3)
			(stroke
				(width 0.12)
				(type solid)
			)
			(layer "B.Fab")
		)
		(fp_line
			(start -3.8 -8.5)
			(end -5.1 -8.8)
			(stroke
				(width 0.12)
				(type solid)
			)
			(layer "B.Fab")
		)
		(fp_line
			(start -1 -8.5)
			(end -2.3 -8.6)
			(stroke
				(width 0.12)
				(type solid)
			)
			(layer "B.Fab")
		)
		(fp_line
			(start 0.8 -8.5)
			(end -1 -8.5)
			(stroke
				(width 0.12)
				(type solid)
			)
			(layer "B.Fab")
		)
		(fp_line
			(start -2.3 -8.6)
			(end -3.8 -8.8)
			(stroke
				(width 0.12)
				(type solid)
			)
			(layer "B.Fab")
		)
		(fp_line
			(start 2.1 -8.6)
			(end 0.8 -8.5)
			(stroke
				(width 0.12)
				(type solid)
			)
			(layer "B.Fab")
		)
		(fp_line
			(start 2.9 -8.7)
			(end 2.1 -8.6)
			(stroke
				(width 0.12)
				(type solid)
			)
			(layer "B.Fab")
		)
		(fp_line
			(start 4.6 -8.7)
			(end 2.9 -8.4)
			(stroke
				(width 0.12)
				(type solid)
			)
			(layer "B.Fab")
		)
		(fp_line
			(start -5.1 -8.8)
			(end -5.6 -8.9)
			(stroke
				(width 0.12)
				(type solid)
			)
			(layer "B.Fab")
		)
		(fp_line
			(start -3.8 -8.8)
			(end -5.1 -9.1)
			(stroke
				(width 0.12)
				(type solid)
			)
			(layer "B.Fab")
		)
		(fp_line
			(start 5.4 -8.9)
			(end 4.6 -8.7)
			(stroke
				(width 0.12)
				(type solid)
			)
			(layer "B.Fab")
		)
		(fp_line
			(start 4.6 -9)
			(end 2.9 -8.7)
			(stroke
				(width 0.12)
				(type solid)
			)
			(layer "B.Fab")
		)
		(fp_line
			(start -5.1 -9.1)
			(end -5.6 -9.2)
			(stroke
				(width 0.12)
				(type solid)
			)
			(layer "B.Fab")
		)
		(fp_line
			(start 5.4 -9.2)
			(end 4.6 -9)
			(stroke
				(width 0.12)
				(type solid)
			)
			(layer "B.Fab")
		)
		(fp_line
			(start 5.4 -9.5)
			(end 5.4 -5.8)
			(stroke
				(width 0.12)
				(type solid)
			)
			(layer "B.Fab")
		)
		(fp_line
			(start 4.9 -10)
			(end -5.1 -10)
			(stroke
				(width 0.12)
				(type solid)
			)
			(layer "B.Fab")
		)
		(fp_rect
			(start -6 5.8)
			(end 5.999 -5.799)
			(stroke
				(width 0.1)
				(type solid)
			)
			(fill no)
			(layer "B.Fab")
		)
		(fp_arc
			(start -5.6 -9.5)
			(mid -5.453553 -9.853553)
			(end -5.1 -10)
			(stroke
				(width 0.12)
				(type solid)
			)
			(layer "B.Fab")
		)
		(fp_arc
			(start 4.9 -10)
			(mid 5.253553 -9.853553)
			(end 5.4 -9.5)
			(stroke
				(width 0.12)
				(type solid)
			)
			(layer "B.Fab")
		)
		(fp_text user "License: Apache-2.0"
			(at -6.925 -15.4 90)
			(layer "B.Fab")
			(effects
				(font
					(size 0.7 0.7)
					(thickness 0.15)
				)
				(justify left bottom mirror)
			)
		)
		(fp_text user "${REFERENCE}"
			(at -6.925 -12.774 90)
			(layer "B.Fab")
			(effects
				(font
					(size 0.7 0.7)
					(thickness 0.15)
				)
				(justify left bottom mirror)
			)
		)
		(fp_text user "Author: Antmicro"
			(at -6.925 -14.1 90)
			(layer "B.Fab")
			(effects
				(font
					(size 0.7 0.7)
					(thickness 0.15)
				)
				(justify left bottom mirror)
			)
		)
		(pad "1" smd rect
			(at 3.124 -5.254 90)
			(size 0.7 1.75)
			(layers "B.Cu" "B.Mask" "B.Paste")
			(net 12 "/Compute module/SDIO.D2")
			(pinfunction "DAT2")
			(pintype "bidirectional")
		)
		(pad "2" smd rect
			(at 2.024 -5.254 90)
			(size 0.7 1.75)
			(layers "B.Cu" "B.Mask" "B.Paste")
			(net 11 "/Compute module/SDIO.D3")
			(pinfunction "CD/DAT3")
			(pintype "bidirectional")
		)
		(pad "3" smd rect
			(at 0.925 -5.254 90)
			(size 0.7 1.75)
			(layers "B.Cu" "B.Mask" "B.Paste")
			(net 8 "/Compute module/SDIO.CMD")
			(pinfunction "CMD")
			(pintype "bidirectional")
		)
		(pad "4" smd rect
			(at -0.176 -5.254 90)
			(size 0.7 1.75)
			(layers "B.Cu" "B.Mask" "B.Paste")
			(net 9 "+3V3")
			(pinfunction "VDD")
			(pintype "power_in")
		)
		(pad "5" smd rect
			(at -1.276 -5.254 90)
			(size 0.7 1.75)
			(layers "B.Cu" "B.Mask" "B.Paste")
			(net 7 "/Compute module/SDIO.CLK")
			(pinfunction "CLK")
			(pintype "output")
		)
		(pad "6" smd rect
			(at -2.375 -5.254 90)
			(size 0.7 1.75)
			(layers "B.Cu" "B.Mask" "B.Paste")
			(net 3 "GND")
			(pinfunction "VSS")
			(pintype "power_in")
		)
		(pad "7" smd rect
			(at -3.476 -5.254 90)
			(size 0.7 1.75)
			(layers "B.Cu" "B.Mask" "B.Paste")
			(net 6 "/Compute module/SDIO.D0")
			(pinfunction "DAT0")
			(pintype "bidirectional")
		)
		(pad "8" smd rect
			(at -4.576 -5.254 90)
			(size 0.7 1.75)
			(layers "B.Cu" "B.Mask" "B.Paste")
			(net 5 "/Compute module/SDIO.D1")
			(pinfunction "DAT1")
			(pintype "bidirectional")
		)
		(pad "9" smd rect
			(at -5.675 4.05 270)
			(size 1.4 1)
			(layers "B.Cu" "B.Mask" "B.Paste")
			(net 268 "Net-(J502-CD1)")
			(pinfunction "CD1")
			(pintype "passive")
		)
		(pad "10" smd rect
			(at 5.424 5.531 180)
			(size 1.4 1)
			(layers "B.Cu" "B.Mask" "B.Paste")
			(net 263 "Net-(J502-CD2)")
			(pinfunction "CD2")
			(pintype "passive")
		)
		(pad "SH" smd rect
			(at -5.976 2.48 180)
			(size 1.5 0.8)
			(layers "B.Cu" "B.Mask" "B.Paste")
			(net 3 "GND")
			(pinfunction "Shell")
			(pintype "passive")
		)
		(pad "SH" smd rect
			(at -5.776 -5.129 270)
			(size 1.3 1.5)
			(layers "B.Cu" "B.Mask" "B.Paste")
			(net 3 "GND")
			(pinfunction "Shell")
			(pintype "passive")
		)
		(pad "SH" smd rect
			(at 5.575 -5.129 270)
			(size 1.5 1.5)
			(layers "B.Cu" "B.Mask" "B.Paste")
			(net 3 "GND")
			(pinfunction "Shell")
			(pintype "passive")
		)
		(pad "SH" smd rect
			(at 5.874 3.13 180)
			(size 1.5 0.8)
			(layers "B.Cu" "B.Mask" "B.Paste")
			(net 3 "GND")
			(pinfunction "Shell")
			(pintype "passive")
		)
	)
)
